;EXTENTS: -5.000  -9.976  75.000  70.024  
;LEADER: 12 
;HEADER: 
;CODE  : ASCII 
;FILE  : E:/<user>/9332_F0TG_MB_C/brd/0417/artwork/9332_F0TG_MB_C_V02_0417_0820_1-18.rou for board E:/<user>/9332_F0TG_MB_C/brd/0417/#Taaaanl41824.tmp, layers TOP to BOTTOM
%
G90
F1
M16
T04
M16
G00X0925990Y0321654
G40
M15
G01X0931490Y0321654
M16
T03
M16
G00X0365287Y0185236
G40
M15
G01X0371587Y0185236
M16
G00X0247176Y0185236
G40
M15
G01X0253476Y0185236
M16
T01
M16
G00X0919791Y0154311
G40
M15
G01X0925091Y0154311
M16
G00X0919791Y0243798
G40
M15
G01X0925091Y0243798
M16
T02
M16
G00X0652975Y0734588
G40
M15
G01X0657875Y0734588
M16
G00X0652975Y1021399
G40
M15
G01X0657875Y1021399
M16
G00X0652975Y1277698
G40
M15
G01X0657875Y1277698
M16
G00X0712377Y0734588
G40
M15
G01X0717277Y0734588
M16
G00X0712377Y1021399
G40
M15
G01X0717277Y1021399
M16
G00X0712377Y1277698
G40
M15
G01X0717277Y1277698
M16
G00X0771779Y0734588
G40
M15
G01X0776679Y0734588
M16
G00X0771779Y1021399
G40
M15
G01X0776679Y1021399
M16
G00X0771779Y1277698
G40
M15
G01X0776679Y1277698
M16
G00X1658818Y0734587
G40
M15
G01X1663718Y0734587
M16
G00X1658818Y1021397
G40
M15
G01X1663718Y1021397
M16
G00X1658818Y1277697
G40
M15
G01X1663718Y1277697
M16
G00X1718220Y0734587
G40
M15
G01X1723120Y0734587
M16
G00X1718220Y1021397
G40
M15
G01X1723120Y1021397
M16
G00X1718220Y1277697
G40
M15
G01X1723120Y1277697
M16
G00X1777620Y0734587
G40
M15
G01X1782520Y0734587
M16
G00X1777620Y1021397
G40
M15
G01X1782520Y1021397
M16
G00X1777620Y1277697
G40
M15
G01X1782520Y1277697
M16
G00X0801479Y0734588
G40
M15
G01X0806379Y0734588
M16
G00X0801479Y1021399
G40
M15
G01X0806379Y1021399
M16
G00X0801479Y1277698
G40
M15
G01X0806379Y1277698
M16
G00X0074944Y0734588
G40
M15
G01X0079844Y0734588
M16
G00X0074944Y1021399
G40
M15
G01X0079844Y1021399
M16
G00X0074944Y1277698
G40
M15
G01X0079844Y1277698
M16
G00X0104645Y0734588
G40
M15
G01X0109545Y0734588
M16
G00X0104645Y1021399
G40
M15
G01X0109545Y1021399
M16
G00X0104645Y1277698
G40
M15
G01X0109545Y1277698
M16
G00X0134345Y0734588
G40
M15
G01X0139245Y0734588
M16
G00X0134345Y1021399
G40
M15
G01X0139245Y1021399
M16
G00X0134345Y1277698
G40
M15
G01X0139245Y1277698
M16
G00X0742078Y0734588
G40
M15
G01X0746978Y0734588
M16
G00X0742078Y1021399
G40
M15
G01X0746978Y1021399
M16
G00X0742078Y1277698
G40
M15
G01X0746978Y1277698
M16
G00X0164046Y0734588
G40
M15
G01X0168946Y0734588
M16
G00X0164046Y1021399
G40
M15
G01X0168946Y1021399
M16
G00X0164046Y1277698
G40
M15
G01X0168946Y1277698
M16
G00X0682676Y0734588
G40
M15
G01X0687576Y0734588
M16
G00X0682676Y1021399
G40
M15
G01X0687576Y1021399
M16
G00X0682676Y1277698
G40
M15
G01X0687576Y1277698
M16
G00X0193747Y0734588
G40
M15
G01X0198647Y0734588
M16
G00X0193747Y1021399
G40
M15
G01X0198647Y1021399
M16
G00X0193747Y1277698
G40
M15
G01X0198647Y1277698
M16
G00X0223448Y0734588
G40
M15
G01X0228348Y0734588
M16
G00X0223448Y1021399
G40
M15
G01X0228348Y1021399
M16
G00X0223448Y1277698
G40
M15
G01X0228348Y1277698
M16
G00X1051086Y0734587
G40
M15
G01X1055986Y0734587
M16
G00X1051086Y1021397
G40
M15
G01X1055986Y1021397
M16
G00X1051086Y1277697
G40
M15
G01X1055986Y1277697
M16
G00X1080787Y0734587
G40
M15
G01X1085687Y0734587
M16
G00X1080787Y1021397
G40
M15
G01X1085687Y1021397
M16
G00X1080787Y1277697
G40
M15
G01X1085687Y1277697
M16
G00X1747920Y0734587
G40
M15
G01X1752820Y0734587
M16
G00X1747920Y1021397
G40
M15
G01X1752820Y1021397
M16
G00X1747920Y1277697
G40
M15
G01X1752820Y1277697
M16
G00X1110487Y0734587
G40
M15
G01X1115387Y0734587
M16
G00X1110487Y1021397
G40
M15
G01X1115387Y1021397
M16
G00X1110487Y1277697
G40
M15
G01X1115387Y1277697
M16
G00X1688518Y0734587
G40
M15
G01X1693418Y0734587
M16
G00X1688518Y1021397
G40
M15
G01X1693418Y1021397
M16
G00X1688518Y1277697
G40
M15
G01X1693418Y1277697
M16
G00X1140188Y0734587
G40
M15
G01X1145088Y0734587
M16
G00X1140188Y1021397
G40
M15
G01X1145088Y1021397
M16
G00X1140188Y1277697
G40
M15
G01X1145088Y1277697
M16
G00X1629117Y0734587
G40
M15
G01X1634017Y0734587
M16
G00X1629117Y1021397
G40
M15
G01X1634017Y1021397
M16
G00X1629117Y1277697
G40
M15
G01X1634017Y1277697
M16
G00X1169889Y0734587
G40
M15
G01X1174789Y0734587
M16
G00X1169889Y1021397
G40
M15
G01X1174789Y1021397
M16
G00X1169889Y1277697
G40
M15
G01X1174789Y1277697
M16
G00X1199590Y0734587
G40
M15
G01X1204490Y0734587
M16
G00X1199590Y1021397
G40
M15
G01X1204490Y1021397
M16
G00X1199590Y1277697
G40
M15
G01X1204490Y1277697
M16
G40
M30
